(kicad_pcb
	(version 20260206)
	(generator "pcbnew")
	(generator_version "10.0")
	(general
		(thickness 1.6)
		(legacy_teardrops no)
	)
	(paper "A4")
	(title_block
		(title "baseboard — 13948-1b.1110WZS1818.brd")
		(comment 1 "Honey Badger (Wiwynn) / footprints 426-433 of 2523")
	)
	(layers
		(0 "F.Cu" signal "TOP")
		(4 "In1.Cu" signal "L2GND")
		(6 "In2.Cu" signal "L3")
		(8 "In3.Cu" signal "L4VCC")
		(10 "In4.Cu" signal "L5VCC")
		(12 "In5.Cu" signal "L6")
		(14 "In6.Cu" signal "L7GND")
		(2 "B.Cu" signal "BOTTOM")
		(9 "F.Adhes" user "F.Adhesive")
		(11 "B.Adhes" user "B.Adhesive")
		(13 "F.Paste" user "Package Geometry/Pastemask Top")
		(15 "B.Paste" user "Package Geometry/Pastemask Bottom")
		(5 "F.SilkS" user "Ref Des/Silkscreen Top")
		(7 "B.SilkS" user "Ref Des/Silkscreen Bottom")
		(1 "F.Mask" user "Board Geometry/Soldermask Top")
		(3 "B.Mask" user "Board Geometry/Soldermask Bottom")
		(17 "Dwgs.User" user "User.Drawings")
		(19 "Cmts.User" user "User.Comments")
		(21 "Eco1.User" user "User.Eco1")
		(23 "Eco2.User" user "User.Eco2")
		(25 "Edge.Cuts" user "Board Geometry/Outline")
		(27 "Margin" user)
		(31 "F.CrtYd" user "Package Geometry/Place Bound Top")
		(29 "B.CrtYd" user "Package Geometry/Place Bound Bottom")
		(35 "F.Fab" user "Ref Des/Assembly Top")
		(33 "B.Fab" user "Ref Des/Assembly Bottom")
	)
	(footprint ""
		(layer "F.Cu")
		(at 86.49716 -44.577 -90)
		(property "Reference" "SC901"
			(at 0 0 270)
			(layer "F.SilkS")
			(hide yes)
			(effects
				(font
					(size 1.27 1.27)
				)
			)
		)
		(property "Value" "SCD01U10V1KX-GP"
			(at -2.8321 -1.7399 270)
			(unlocked yes)
			(layer "F.Fab")
			(hide yes)
			(effects
				(font
					(size 1.016 1.016)
					(thickness 0.1524)
				)
			)
		)
		(property "Device Type" "C0201H13"
			(at -2.8321 -3.2639 270)
			(unlocked yes)
			(layer "F.Fab")
			(hide yes)
			(effects
				(font
					(size 1.016 1.016)
					(thickness 0.1524)
				)
			)
		)
		(duplicate_pad_numbers_are_jumpers no)
		(fp_rect
			(start -0.2794 0.6477)
			(end 0.2794 -0.6477)
			(stroke
				(width 0)
				(type default)
			)
			(fill no)
			(layer "F.CrtYd")
		)
		(fp_rect
			(start -0.2794 0.6477)
			(end 0.2794 -0.6477)
			(stroke
				(width 0)
				(type default)
			)
			(fill no)
			(layer "F.Fab")
		)
		(pad "1" smd custom
			(at 0 -0.2794 270)
			(size 0.0762 0.0762)
			(layers "F.Cu" "F.Mask" "F.Paste")
			(net "SAS3008_RAID_TX_C_N4")
			(options
				(clearance outline)
				(anchor circle)
			)
			(primitives
				(gr_poly
					(pts
						(arc
							(start 0.1524 -0.127)
							(mid 0.137521 -0.162921)
							(end 0.1016 -0.1778)
						)
						(arc
							(start -0.1016 -0.1778)
							(mid -0.137521 -0.162921)
							(end -0.1524 -0.127)
						)
						(arc
							(start -0.1524 0.127)
							(mid -0.137521 0.162921)
							(end -0.1016 0.1778)
						)
						(arc
							(start 0.1016 0.1778)
							(mid 0.137521 0.162921)
							(end 0.1524 0.127)
						)
					)
					(width 0)
					(fill yes)
				)
			)
		)
		(pad "2" smd custom
			(at 0 0.2794 270)
			(size 0.0762 0.0762)
			(layers "F.Cu" "F.Mask" "F.Paste")
			(net "IOC_RAID_TX_N4")
			(options
				(clearance outline)
				(anchor circle)
			)
			(primitives
				(gr_poly
					(pts
						(arc
							(start 0.1524 -0.127)
							(mid 0.137521 -0.162921)
							(end 0.1016 -0.1778)
						)
						(arc
							(start -0.1016 -0.1778)
							(mid -0.137521 -0.162921)
							(end -0.1524 -0.127)
						)
						(arc
							(start -0.1524 0.127)
							(mid -0.137521 0.162921)
							(end -0.1016 0.1778)
						)
						(arc
							(start 0.1016 0.1778)
							(mid 0.137521 0.162921)
							(end 0.1524 0.127)
						)
					)
					(width 0)
					(fill yes)
				)
			)
		)
	)
	(footprint ""
		(layer "F.Cu")
		(at 310.896 -188.087 90)
		(property "Reference" "R304"
			(at 0 0 90)
			(layer "F.SilkS")
			(hide yes)
			(effects
				(font
					(size 1.27 1.27)
				)
			)
		)
		(property "Value" "0R2J-2-GP"
			(at 0.064008 -3.993896 90)
			(unlocked yes)
			(layer "F.Fab")
			(hide yes)
			(effects
				(font
					(size 1.016 1.016)
					(thickness 0.1524)
				)
			)
		)
		(property "Device Type" "R402H16"
			(at 0.064008 -5.517896 90)
			(unlocked yes)
			(layer "F.Fab")
			(hide yes)
			(effects
				(font
					(size 1.016 1.016)
					(thickness 0.1524)
				)
			)
		)
		(duplicate_pad_numbers_are_jumpers no)
		(fp_line
			(start 0.508 -0.9398)
			(end -0.508 -0.9398)
			(stroke
				(width 0.1524)
				(type default)
			)
			(layer "F.SilkS")
		)
		(fp_line
			(start -0.508 -0.9398)
			(end -0.508 0.9398)
			(stroke
				(width 0.1524)
				(type default)
			)
			(layer "F.SilkS")
		)
		(fp_rect
			(start -0.508 0.9398)
			(end 0.508 -0.9398)
			(stroke
				(width 0)
				(type default)
			)
			(fill no)
			(layer "F.CrtYd")
		)
		(fp_rect
			(start -0.508 0.9398)
			(end 0.508 -0.9398)
			(stroke
				(width 0)
				(type default)
			)
			(fill no)
			(layer "F.Fab")
		)
		(pad "1" smd custom
			(at 0 -0.4445 90)
			(size 0.1397 0.1397)
			(layers "F.Cu" "F.Mask" "F.Paste")
			(net "HB0_R_IN2")
			(options
				(clearance outline)
				(anchor circle)
			)
			(primitives
				(gr_poly
					(pts
						(arc
							(start -0.1778 -0.2794)
							(mid -0.249642 -0.249642)
							(end -0.2794 -0.1778)
						)
						(arc
							(start -0.2794 0.1778)
							(mid -0.249642 0.249642)
							(end -0.1778 0.2794)
						)
						(arc
							(start 0.1778 0.2794)
							(mid 0.249642 0.249642)
							(end 0.2794 0.1778)
						)
						(arc
							(start 0.2794 -0.1778)
							(mid 0.249642 -0.249642)
							(end 0.1778 -0.2794)
						)
					)
					(width 0)
					(fill yes)
				)
			)
		)
		(pad "2" smd custom
			(at 0 0.4445 90)
			(size 0.1397 0.1397)
			(layers "F.Cu" "F.Mask" "F.Paste")
			(net "HB_B_SIDE_IN")
			(options
				(clearance outline)
				(anchor circle)
			)
			(primitives
				(gr_poly
					(pts
						(arc
							(start -0.1778 -0.2794)
							(mid -0.249642 -0.249642)
							(end -0.2794 -0.1778)
						)
						(arc
							(start -0.2794 0.1778)
							(mid -0.249642 0.249642)
							(end -0.1778 0.2794)
						)
						(arc
							(start 0.1778 0.2794)
							(mid 0.249642 0.249642)
							(end 0.2794 0.1778)
						)
						(arc
							(start 0.2794 -0.1778)
							(mid 0.249642 -0.249642)
							(end 0.1778 -0.2794)
						)
					)
					(width 0)
					(fill yes)
				)
			)
		)
	)
	(footprint ""
		(layer "F.Cu")
		(at 335.534 -4.318 90)
		(property "Reference" "LED15"
			(at 0 0 90)
			(layer "F.SilkS")
			(hide yes)
			(effects
				(font
					(size 1.27 1.27)
				)
			)
		)
		(property "Value" "LED-Y-11-GP"
			(at -0.1016 -8.1788 90)
			(unlocked yes)
			(layer "F.Fab")
			(hide yes)
			(effects
				(font
					(size 1.016 1.016)
					(thickness 0.1524)
				)
			)
		)
		(property "Device Type" "19-21UBC-1"
			(at -0.0508 -9.8552 90)
			(unlocked yes)
			(layer "F.Fab")
			(hide yes)
			(effects
				(font
					(size 1.016 1.016)
					(thickness 0.1524)
				)
			)
		)
		(duplicate_pad_numbers_are_jumpers no)
		(fp_line
			(start 1.4351 -0.7747)
			(end 1.4351 0.7747)
			(stroke
				(width 0.1524)
				(type default)
			)
			(layer "F.SilkS")
		)
		(fp_line
			(start -1.4351 -0.7747)
			(end 1.4351 -0.7747)
			(stroke
				(width 0.1524)
				(type default)
			)
			(layer "F.SilkS")
		)
		(fp_line
			(start -1.7653 -0.7747)
			(end -1.7653 0.7747)
			(stroke
				(width 0.508)
				(type default)
			)
			(layer "F.SilkS")
		)
		(fp_line
			(start 1.4351 0.7747)
			(end -1.4351 0.7747)
			(stroke
				(width 0.1524)
				(type default)
			)
			(layer "F.SilkS")
		)
		(fp_line
			(start -1.4351 0.7747)
			(end -1.4351 -0.7747)
			(stroke
				(width 0.1524)
				(type default)
			)
			(layer "F.SilkS")
		)
		(fp_rect
			(start -2.0193 1.0287)
			(end 1.6891 -1.0287)
			(stroke
				(width 0)
				(type default)
			)
			(fill no)
			(layer "F.CrtYd")
		)
		(fp_poly
			(pts
				(xy -2.0193 -1.0287) (xy -2.0193 1.0287) (xy 1.6891 1.0287) (xy 1.6891 -1.0287)
			)
			(stroke
				(width 0)
				(type default)
			)
			(fill no)
			(layer "F.Fab")
		)
		(pad "1" smd rect
			(at -0.7112 0 90)
			(size 0.9398 1.0668)
			(layers "F.Cu" "F.Mask" "F.Paste")
			(net "DEBUG CONSOLE_LED_1")
		)
		(pad "2" smd rect
			(at 0.7112 0 90)
			(size 0.9398 1.0668)
			(layers "F.Cu" "F.Mask" "F.Paste")
			(net "CONSOLE_LED_1")
		)
	)
	(footprint ""
		(layer "F.Cu")
		(at 221.860872 -178.634136)
		(property "Reference" "R498"
			(at 0 0 0)
			(layer "F.SilkS")
			(hide yes)
			(effects
				(font
					(size 1.27 1.27)
				)
			)
		)
		(property "Value" "0R2J-2-GP"
			(at 0.064008 -3.993896 0)
			(unlocked yes)
			(layer "F.Fab")
			(hide yes)
			(effects
				(font
					(size 1.016 1.016)
					(thickness 0.1524)
				)
			)
		)
		(property "Device Type" "R402H16"
			(at 0.064008 -5.517896 0)
			(unlocked yes)
			(layer "F.Fab")
			(hide yes)
			(effects
				(font
					(size 1.016 1.016)
					(thickness 0.1524)
				)
			)
		)
		(duplicate_pad_numbers_are_jumpers no)
		(fp_line
			(start -0.508 -0.9398)
			(end -0.508 0.9398)
			(stroke
				(width 0.1524)
				(type default)
			)
			(layer "F.SilkS")
		)
		(fp_line
			(start 0.508 -0.9398)
			(end -0.508 -0.9398)
			(stroke
				(width 0.1524)
				(type default)
			)
			(layer "F.SilkS")
		)
		(fp_rect
			(start -0.508 0.9398)
			(end 0.508 -0.9398)
			(stroke
				(width 0)
				(type default)
			)
			(fill no)
			(layer "F.CrtYd")
		)
		(fp_rect
			(start -0.508 0.9398)
			(end 0.508 -0.9398)
			(stroke
				(width 0)
				(type default)
			)
			(fill no)
			(layer "F.Fab")
		)
		(pad "1" smd custom
			(at 0 -0.4445)
			(size 0.1397 0.1397)
			(layers "F.Cu" "F.Mask" "F.Paste")
			(net "HB_A_OUT_EXP")
			(options
				(clearance outline)
				(anchor circle)
			)
			(primitives
				(gr_poly
					(pts
						(arc
							(start -0.1778 -0.2794)
							(mid -0.249642 -0.249642)
							(end -0.2794 -0.1778)
						)
						(arc
							(start -0.2794 0.1778)
							(mid -0.249642 0.249642)
							(end -0.1778 0.2794)
						)
						(arc
							(start 0.1778 0.2794)
							(mid 0.249642 0.249642)
							(end 0.2794 0.1778)
						)
						(arc
							(start 0.2794 -0.1778)
							(mid 0.249642 -0.249642)
							(end 0.1778 -0.2794)
						)
					)
					(width 0)
					(fill yes)
				)
			)
		)
		(pad "2" smd custom
			(at 0 0.4445)
			(size 0.1397 0.1397)
			(layers "F.Cu" "F.Mask" "F.Paste")
			(net "INVERTER_G1_EXP")
			(options
				(clearance outline)
				(anchor circle)
			)
			(primitives
				(gr_poly
					(pts
						(arc
							(start -0.1778 -0.2794)
							(mid -0.249642 -0.249642)
							(end -0.2794 -0.1778)
						)
						(arc
							(start -0.2794 0.1778)
							(mid -0.249642 0.249642)
							(end -0.1778 0.2794)
						)
						(arc
							(start 0.1778 0.2794)
							(mid 0.249642 0.249642)
							(end 0.2794 0.1778)
						)
						(arc
							(start 0.2794 -0.1778)
							(mid 0.249642 -0.249642)
							(end 0.1778 -0.2794)
						)
					)
					(width 0)
					(fill yes)
				)
			)
		)
	)
	(footprint ""
		(layer "F.Cu")
		(at 77.343 -20.701 90)
		(property "Reference" "PSP3"
			(at 0 0 90)
			(layer "F.SilkS")
			(hide yes)
			(effects
				(font
					(size 1.27 1.27)
				)
			)
		)
		(property "Value" "COPPER-CLOSE-GP-U"
			(at 0.0762 -2.8702 90)
			(unlocked yes)
			(layer "F.Fab")
			(hide yes)
			(effects
				(font
					(size 1.016 1.016)
					(thickness 0.1524)
				)
			)
		)
		(property "Device Type" "CON2C-U"
			(at 0.0762 -4.3942 90)
			(unlocked yes)
			(layer "F.Fab")
			(hide yes)
			(effects
				(font
					(size 1.016 1.016)
					(thickness 0.1524)
				)
			)
		)
		(duplicate_pad_numbers_are_jumpers no)
		(fp_rect
			(start -0.9398 0.9652)
			(end 0.9398 -0.9652)
			(stroke
				(width 0)
				(type default)
			)
			(fill no)
			(layer "F.CrtYd")
		)
		(fp_rect
			(start -0.9398 0.9652)
			(end 0.9398 -0.9652)
			(stroke
				(width 0)
				(type default)
			)
			(fill no)
			(layer "F.Fab")
		)
		(pad "1" smd custom
			(at 0 -0.5334 90)
			(size 0.17145 0.17145)
			(layers "F.Cu" "F.Mask" "F.Paste")
			(net "GND")
			(options
				(clearance outline)
				(anchor circle)
			)
			(primitives
				(gr_poly
					(pts
						(xy -0.127 0.3429) (xy -0.127 0.1651) (xy -0.635 -0.3429) (xy 0.635 -0.3429) (xy 0.127 0.1651)
						(xy 0.127 0.3429)
					)
					(width 0)
					(fill yes)
				)
			)
		)
		(pad "2" smd custom
			(at 0 0.5334 90)
			(size 0.17145 0.17145)
			(layers "F.Cu" "F.Mask" "F.Paste")
			(net "AGND_P0V9_C")
			(options
				(clearance outline)
				(anchor circle)
			)
			(primitives
				(gr_poly
					(pts
						(xy -0.635 0.3429) (xy -0.127 -0.1651) (xy -0.127 -0.3429) (xy 0.127 -0.3429) (xy 0.127 -0.1651)
						(xy 0.635 0.3429)
					)
					(width 0)
					(fill yes)
				)
			)
		)
	)
	(footprint ""
		(layer "F.Cu")
		(at 318.008 -177.673 -90)
		(property "Reference" "C190"
			(at 0 0 270)
			(layer "F.SilkS")
			(hide yes)
			(effects
				(font
					(size 1.27 1.27)
				)
			)
		)
		(property "Value" "SCD1U16V2KX-3GP"
			(at 1.1811 -2.7051 270)
			(unlocked yes)
			(layer "F.Fab")
			(hide yes)
			(effects
				(font
					(size 1.016 1.016)
					(thickness 0.1524)
				)
			)
		)
		(property "Device Type" "C402H22"
			(at 1.1811 -4.2291 270)
			(unlocked yes)
			(layer "F.Fab")
			(hide yes)
			(effects
				(font
					(size 1.016 1.016)
					(thickness 0.1524)
				)
			)
		)
		(duplicate_pad_numbers_are_jumpers no)
		(fp_rect
			(start -0.4318 0.9525)
			(end 0.4318 -0.9525)
			(stroke
				(width 0)
				(type default)
			)
			(fill no)
			(layer "F.CrtYd")
		)
		(fp_rect
			(start -0.4318 0.9525)
			(end 0.4318 -0.9525)
			(stroke
				(width 0)
				(type default)
			)
			(fill no)
			(layer "F.Fab")
		)
		(pad "1" smd custom
			(at 0 -0.4445 270)
			(size 0.1524 0.1524)
			(layers "F.Cu" "F.Mask" "F.Paste")
			(net "GND")
			(options
				(clearance outline)
				(anchor circle)
			)
			(primitives
				(gr_poly
					(pts
						(arc
							(start 0.3048 -0.2032)
							(mid 0.275042 -0.275042)
							(end 0.2032 -0.3048)
						)
						(arc
							(start -0.2032 -0.3048)
							(mid -0.275042 -0.275042)
							(end -0.3048 -0.2032)
						)
						(arc
							(start -0.3048 0.2032)
							(mid -0.275042 0.275042)
							(end -0.2032 0.3048)
						)
						(arc
							(start 0.2032 0.3048)
							(mid 0.275042 0.275042)
							(end 0.3048 0.2032)
						)
					)
					(width 0)
					(fill yes)
				)
			)
		)
		(pad "2" smd custom
			(at 0 0.4445 270)
			(size 0.1524 0.1524)
			(layers "F.Cu" "F.Mask" "F.Paste")
			(net "ADCVREFFN")
			(options
				(clearance outline)
				(anchor circle)
			)
			(primitives
				(gr_poly
					(pts
						(arc
							(start 0.3048 -0.2032)
							(mid 0.275042 -0.275042)
							(end 0.2032 -0.3048)
						)
						(arc
							(start -0.2032 -0.3048)
							(mid -0.275042 -0.275042)
							(end -0.3048 -0.2032)
						)
						(arc
							(start -0.3048 0.2032)
							(mid -0.275042 0.275042)
							(end -0.2032 0.3048)
						)
						(arc
							(start 0.2032 0.3048)
							(mid 0.275042 0.275042)
							(end 0.3048 0.2032)
						)
					)
					(width 0)
					(fill yes)
				)
			)
		)
	)
	(footprint ""
		(layer "F.Cu")
		(at 119.196612 -205.867 180)
		(property "Reference" "SR875"
			(at 0 0 180)
			(layer "F.SilkS")
			(hide yes)
			(effects
				(font
					(size 1.27 1.27)
				)
			)
		)
		(property "Value" "0R2J-2-GP"
			(at 0.064008 -3.993896 180)
			(unlocked yes)
			(layer "F.Fab")
			(hide yes)
			(effects
				(font
					(size 1.016 1.016)
					(thickness 0.1524)
				)
			)
		)
		(property "Device Type" "R402H16"
			(at 0.064008 -5.517896 180)
			(unlocked yes)
			(layer "F.Fab")
			(hide yes)
			(effects
				(font
					(size 1.016 1.016)
					(thickness 0.1524)
				)
			)
		)
		(duplicate_pad_numbers_are_jumpers no)
		(fp_line
			(start 0.508 -0.9398)
			(end -0.508 -0.9398)
			(stroke
				(width 0.1524)
				(type default)
			)
			(layer "F.SilkS")
		)
		(fp_line
			(start -0.508 -0.9398)
			(end -0.508 0.9398)
			(stroke
				(width 0.1524)
				(type default)
			)
			(layer "F.SilkS")
		)
		(fp_rect
			(start -0.508 0.9398)
			(end 0.508 -0.9398)
			(stroke
				(width 0)
				(type default)
			)
			(fill no)
			(layer "F.CrtYd")
		)
		(fp_rect
			(start -0.508 0.9398)
			(end 0.508 -0.9398)
			(stroke
				(width 0)
				(type default)
			)
			(fill no)
			(layer "F.Fab")
		)
		(pad "1" smd custom
			(at 0 -0.4445 180)
			(size 0.1397 0.1397)
			(layers "F.Cu" "F.Mask" "F.Paste")
			(net "SAS_HDD_REDV_TX7_N")
			(options
				(clearance outline)
				(anchor circle)
			)
			(primitives
				(gr_poly
					(pts
						(arc
							(start -0.1778 -0.2794)
							(mid -0.249642 -0.249642)
							(end -0.2794 -0.1778)
						)
						(arc
							(start -0.2794 0.1778)
							(mid -0.249642 0.249642)
							(end -0.1778 0.2794)
						)
						(arc
							(start 0.1778 0.2794)
							(mid 0.249642 0.249642)
							(end 0.2794 0.1778)
						)
						(arc
							(start 0.2794 -0.1778)
							(mid 0.249642 -0.249642)
							(end 0.1778 -0.2794)
						)
					)
					(width 0)
					(fill yes)
				)
			)
		)
		(pad "2" smd custom
			(at 0 0.4445 180)
			(size 0.1397 0.1397)
			(layers "F.Cu" "F.Mask" "F.Paste")
			(net "REDV_TX7_N")
			(options
				(clearance outline)
				(anchor circle)
			)
			(primitives
				(gr_poly
					(pts
						(arc
							(start -0.1778 -0.2794)
							(mid -0.249642 -0.249642)
							(end -0.2794 -0.1778)
						)
						(arc
							(start -0.2794 0.1778)
							(mid -0.249642 0.249642)
							(end -0.1778 0.2794)
						)
						(arc
							(start 0.1778 0.2794)
							(mid 0.249642 0.249642)
							(end 0.2794 0.1778)
						)
						(arc
							(start 0.2794 -0.1778)
							(mid 0.249642 -0.249642)
							(end 0.1778 -0.2794)
						)
					)
					(width 0)
					(fill yes)
				)
			)
		)
	)
	(footprint ""
		(layer "F.Cu")
		(at 332.096872 -232.482136)
		(property "Reference" "R179"
			(at 0 0 0)
			(layer "F.SilkS")
			(hide yes)
			(effects
				(font
					(size 1.27 1.27)
				)
			)
		)
		(property "Value" "0R2J-2-GP"
			(at 0.064008 -3.993896 0)
			(unlocked yes)
			(layer "F.Fab")
			(hide yes)
			(effects
				(font
					(size 1.016 1.016)
					(thickness 0.1524)
				)
			)
		)
		(property "Device Type" "R402H16"
			(at 0.064008 -5.517896 0)
			(unlocked yes)
			(layer "F.Fab")
			(hide yes)
			(effects
				(font
					(size 1.016 1.016)
					(thickness 0.1524)
				)
			)
		)
		(duplicate_pad_numbers_are_jumpers no)
		(fp_line
			(start -0.508 -0.9398)
			(end -0.508 0.9398)
			(stroke
				(width 0.1524)
				(type default)
			)
			(layer "F.SilkS")
		)
		(fp_line
			(start 0.508 -0.9398)
			(end -0.508 -0.9398)
			(stroke
				(width 0.1524)
				(type default)
			)
			(layer "F.SilkS")
		)
		(fp_rect
			(start -0.508 0.9398)
			(end 0.508 -0.9398)
			(stroke
				(width 0)
				(type default)
			)
			(fill no)
			(layer "F.CrtYd")
		)
		(fp_rect
			(start -0.508 0.9398)
			(end 0.508 -0.9398)
			(stroke
				(width 0)
				(type default)
			)
			(fill no)
			(layer "F.Fab")
		)
		(pad "1" smd custom
			(at 0 -0.4445)
			(size 0.1397 0.1397)
			(layers "F.Cu" "F.Mask" "F.Paste")
			(net "ADC_12V")
			(options
				(clearance outline)
				(anchor circle)
			)
			(primitives
				(gr_poly
					(pts
						(arc
							(start -0.1778 -0.2794)
							(mid -0.249642 -0.249642)
							(end -0.2794 -0.1778)
						)
						(arc
							(start -0.2794 0.1778)
							(mid -0.249642 0.249642)
							(end -0.1778 0.2794)
						)
						(arc
							(start 0.1778 0.2794)
							(mid 0.249642 0.249642)
							(end 0.2794 0.1778)
						)
						(arc
							(start 0.2794 -0.1778)
							(mid 0.249642 -0.249642)
							(end 0.1778 -0.2794)
						)
					)
					(width 0)
					(fill yes)
				)
			)
		)
		(pad "2" smd custom
			(at 0 0.4445)
			(size 0.1397 0.1397)
			(layers "F.Cu" "F.Mask" "F.Paste")
			(net "12V_SENSE")
			(options
				(clearance outline)
				(anchor circle)
			)
			(primitives
				(gr_poly
					(pts
						(arc
							(start -0.1778 -0.2794)
							(mid -0.249642 -0.249642)
							(end -0.2794 -0.1778)
						)
						(arc
							(start -0.2794 0.1778)
							(mid -0.249642 0.249642)
							(end -0.1778 0.2794)
						)
						(arc
							(start 0.1778 0.2794)
							(mid 0.249642 0.249642)
							(end 0.2794 0.1778)
						)
						(arc
							(start 0.2794 -0.1778)
							(mid 0.249642 -0.249642)
							(end 0.1778 -0.2794)
						)
					)
					(width 0)
					(fill yes)
				)
			)
		)
	)
)
